#ISCELL
  mstr_misc dns *
  *
#ISCELL
  pure_quanta quanta_title_block_c *
  *
#ISCELL
  pure_quanta_power gnd *
  page380_i1
#CELL
  pure_quanta q_cap *
  page380_i10
#CELL
  pure_quanta q_res *
  page380_i11
#CELL
  pure_quanta q_cap *
  page380_i12
#ISCELL
  pure_quanta_power universal_power *
  page380_i13
#ISCELL
  pure_quanta_power gnd *
  page380_i14
#ISCELL
  pure_quanta_power gnd *
  page380_i15
#CELL
  pure_quanta mpq8626gdz *
  page380_i16
#CELL
  pure_quanta q_cap *
  page380_i17
#CELL
  pure_quanta q_cap *
  page380_i18
#CELL
  pure_quanta q_res *
  page380_i19
#CELL
  pure_quanta q_inductor *
  page380_i2
#ISCELL
  pure_quanta_power gnd *
  page380_i20
#CELL
  pure_quanta q_res *
  page380_i21
#ISCELL
  pure_quanta_power gnd *
  page380_i22
#CELL
  pure_quanta q_cap *
  page380_i23
#CELL
  pure_quanta q_inductor *
  page380_i24
#CELL
  pure_quanta q_cap *
  page380_i26
#CELL
  pure_quanta q_res *
  page380_i27
#CELL
  pure_quanta q_cap *
  page380_i28
#CELL
  pure_quanta q_cap *
  page380_i29
#CELL
  pure_quanta q_cap *
  page380_i3
#ISCELL
  pure_quanta_power gnd *
  page380_i30
#ISCELL
  pure_quanta_power universal_power *
  page380_i31
#CELL
  pure_quanta q_cap *
  page380_i32
#CELL
  pure_quanta q_cap *
  page380_i33
#ISCELL
  pure_quanta_power universal_power *
  page380_i34
#CELL
  pure_quanta q_cap *
  page380_i35
#ISCELL
  pure_quanta_power gnd *
  page380_i36
#ISCELL
  pure_quanta_power universal_power *
  page380_i37
#CELL
  pure_quanta q_res *
  page380_i38
#ISCELL
  standard offpage *
  page380_i39
#ISCELL
  pure_quanta_power gnd *
  page380_i4
#CELL
  pure_quanta q_res *
  page380_i40
#CELL
  pure_quanta q_cap *
  page380_i41
#ISCELL
  pure_quanta_power gnd *
  page380_i42
#ISCELL
  standard offpage *
  page380_i43
#CELL
  pure_quanta q_res *
  page380_i44
#CELL
  pure_quanta q_res *
  page380_i45
#ISCELL
  pure_quanta_power gnd *
  page380_i5
#CELL
  pure_quanta q_res *
  page380_i6
#CELL
  pure_quanta q_cap *
  page380_i7
#ISCELL
  pure_quanta_power gnd *
  page380_i8
